(kicad_pcb
	(version 20221018)
	(generator pcbnew)
	(general
    (thickness 1.62)
  )
	(paper "A4")
	(title_block
    (title "ECP5 - Datacenter Secure Control Module (DC-SCM)")
    (date "2024-07-01")
    (rev "1.2.1")
		(comment 9 "footprints 179-182 of 506")
	)
	(layers
    (0 "F.Cu" signal)
    (1 "In1.Cu" power)
    (2 "In2.Cu" signal)
    (3 "In3.Cu" power)
    (4 "In4.Cu" power)
    (5 "In5.Cu" signal)
    (6 "In6.Cu" power)
    (31 "B.Cu" signal)
    (32 "B.Adhes" user "B.Adhesive")
    (33 "F.Adhes" user "F.Adhesive")
    (34 "B.Paste" user)
    (35 "F.Paste" user)
    (36 "B.SilkS" user "B.Silkscreen")
    (37 "F.SilkS" user "F.Silkscreen")
    (38 "B.Mask" user)
    (39 "F.Mask" user)
    (40 "Dwgs.User" user "User.Drawings")
    (41 "Cmts.User" user "User.Comments")
    (42 "Eco1.User" user "User.Eco1")
    (43 "Eco2.User" user "User.Eco2")
    (44 "Edge.Cuts" user)
    (45 "Margin" user)
    (46 "B.CrtYd" user "B.Courtyard")
    (47 "F.CrtYd" user "F.Courtyard")
    (48 "B.Fab" user)
    (49 "F.Fab" user)
  )
	(footprint "antmicro-footprints:Oscillator_SMD_Abracon_ASFLMB_5x3.2x0.85mm" (layer "F.Cu")
    (at 144.631 87.455 180)
    (property "Author" "Antmicro")
    (property "License" "Apache-2.0")
    (property "MPN" "ASFLMB-12.000MHZ-LC-T")
    (property "Manufacturer" "Abracon")
    (property "Sheetfile" "interfaces.kicad_sch")
    (property "Sheetname" "Interfaces")
    (property "Val" "12 MHz")
    (property "ki_description" "MEMS Oscillator, 12 MHz, SMD, 5mm x 3.2mm, 50 ppm, 3.3 V, ASFLMB, LVCMOS")
    (property "ki_keywords" "OSCILLATOR, MEMS")
    (attr smd)
    (fp_text reference "Y4" (at 0.211 3.41) (layer "F.SilkS")
        (effects (font (size 0.7 0.7) (thickness 0.127)))
    )
    (fp_text value "Oscillator_12MHz_ASFLMB" (at -0.05 2.925) (layer "F.Fab")
        (effects (font (size 1 1) (thickness 0.15)))
    )
    (fp_text user "Author: Antmicro" (at -2.8 6.259 180) (layer "F.Fab") hide
        (effects (font (size 0.7 0.7) (thickness 0.15)) (justify left bottom))
    )
    (fp_text user "License: Apache-2.0" (at -2.8 7.459 180) (layer "F.Fab") hide
        (effects (font (size 0.7 0.7) (thickness 0.15)) (justify left bottom))
    )
    (fp_text user "${REFERENCE}" (at -2 0) (layer "F.Fab")
        (effects (font (size 0.3 0.3) (thickness 0.05)))
    )
    (fp_line (start -1.6 -2.5) (end -1.6 -1.9)
      (stroke (width 0.15) (type solid)) (layer "F.SilkS"))
    (fp_line (start -1.6 -0.4) (end -1.6 0.6)
      (stroke (width 0.15) (type solid)) (layer "F.SilkS"))
    (fp_line (start -1.6 2.1) (end -1.6 2.7)
      (stroke (width 0.15) (type solid)) (layer "F.SilkS"))
    (fp_line (start -1.6 2.7) (end 1.8 2.7)
      (stroke (width 0.15) (type solid)) (layer "F.SilkS"))
    (fp_line (start 1.8 -2.5) (end -1.6 -2.5)
      (stroke (width 0.15) (type solid)) (layer "F.SilkS"))
    (fp_line (start 1.8 -1.9) (end 1.8 -2.5)
      (stroke (width 0.15) (type solid)) (layer "F.SilkS"))
    (fp_line (start 1.8 0.6) (end 1.8 -0.4)
      (stroke (width 0.15) (type solid)) (layer "F.SilkS"))
    (fp_line (start 1.8 2.7) (end 1.8 2.1)
      (stroke (width 0.15) (type solid)) (layer "F.SilkS"))
    (fp_circle (center -1.9 -2.1) (end -1.9 -2.05)
      (stroke (width 0.15) (type solid)) (fill solid) (layer "F.SilkS"))
    (fp_rect (start 2 -2.7) (end -1.8 2.9)
      (stroke (width 0.05) (type solid)) (fill none) (layer "F.CrtYd"))
    (pad "1" smd rect (at -1.049 -1.17) (size 1.1 1.2) (layers "F.Cu" "F.Paste" "F.Mask")
      (net 2 "VCC3V3") (pinfunction "EN") (pintype "input"))
    (pad "2" smd rect (at -1.049 1.369 90) (size 1.2 1.1) (layers "F.Cu" "F.Paste" "F.Mask")
      (net 1 "GND") (pinfunction "GND") (pintype "power_in"))
    (pad "3" smd rect (at 1.252 1.369 90) (size 1.2 1.1) (layers "F.Cu" "F.Paste" "F.Mask")
      (net 511 "/Interfaces/FTDI_CLK") (pinfunction "OUT") (pintype "output"))
    (pad "4" smd rect (at 1.252 -1.17 90) (size 1.2 1.1) (layers "F.Cu" "F.Paste" "F.Mask")
      (net 2 "VCC3V3") (pinfunction "VDD") (pintype "power_in"))
  )
	(footprint "antmicro-footprints:TP_SMD_1mm" (layer "F.Cu")
    (at 137.75 96.35 -90)
    (property "Author" "Antmicro")
    (property "License" "Apache-2.0")
    (property "MPN" "")
    (property "Manufacturer" "")
    (property "Sheetfile" "interfaces.kicad_sch")
    (property "Sheetname" "Interfaces")
    (property "exclude_from_bom" "")
    (property "ki_description" "Test point 1mm SMD")
    (property "ki_keywords" "TESTPOINT")
    (attr exclude_from_pos_files exclude_from_bom)
    (fp_text reference "TP15" (at 0.435 -0.66) (layer "F.SilkS")
        (effects (font (size 0.7 0.7) (thickness 0.15)) (justify left bottom))
    )
    (fp_text value "TP_1mm_SMD" (at 0 1.4 -90) (layer "F.Fab")
        (effects (font (size 0.7 0.7) (thickness 0.15)) (justify left bottom))
    )
    (fp_text user "Author: Antmicro" (at -0.5 4 -90) (layer "F.Fab") hide
        (effects (font (size 0.7 0.7) (thickness 0.15)) (justify left bottom))
    )
    (fp_text user "${REFERENCE}" (at -0.5 2.8 -90) (layer "F.Fab") hide
        (effects (font (size 0.7 0.7) (thickness 0.15)) (justify left bottom))
    )
    (fp_text user "License: Apache-2.0" (at -0.5 5.2 -90) (layer "F.Fab") hide
        (effects (font (size 0.7 0.7) (thickness 0.15)) (justify left bottom))
    )
    (fp_circle (center 0 0) (end 0.6 0)
      (stroke (width 0.05) (type default)) (fill none) (layer "F.CrtYd"))
    (pad "1" smd circle (at 0 0 270) (size 1 1) (layers "F.Cu" "F.Mask")
      (net 436 "Net-(U14-~{SUSPEND})") (pinfunction "1") (pintype "passive"))
  )
	(footprint "antmicro-footprints:TP_SMD_1mm" (layer "F.Cu")
    (at 140.9492 84.675 -90)
    (property "Author" "Antmicro")
    (property "License" "Apache-2.0")
    (property "MPN" "")
    (property "Manufacturer" "")
    (property "Sheetfile" "interfaces.kicad_sch")
    (property "Sheetname" "Interfaces")
    (property "exclude_from_bom" "")
    (property "ki_description" "Test point 1mm SMD")
    (property "ki_keywords" "TESTPOINT")
    (attr exclude_from_pos_files exclude_from_bom)
    (fp_text reference "TP14" (at -0.69 1.1392) (layer "F.SilkS")
        (effects (font (size 0.7 0.7) (thickness 0.15)) (justify left bottom))
    )
    (fp_text value "TP_1mm_SMD" (at 0 1.4 -90) (layer "F.Fab")
        (effects (font (size 0.7 0.7) (thickness 0.15)) (justify left bottom))
    )
    (fp_text user "License: Apache-2.0" (at -0.5 5.2 -90) (layer "F.Fab") hide
        (effects (font (size 0.7 0.7) (thickness 0.15)) (justify left bottom))
    )
    (fp_text user "Author: Antmicro" (at -0.5 4 -90) (layer "F.Fab") hide
        (effects (font (size 0.7 0.7) (thickness 0.15)) (justify left bottom))
    )
    (fp_text user "${REFERENCE}" (at -0.5 2.8 -90) (layer "F.Fab") hide
        (effects (font (size 0.7 0.7) (thickness 0.15)) (justify left bottom))
    )
    (fp_circle (center 0 0) (end 0.6 0)
      (stroke (width 0.05) (type default)) (fill none) (layer "F.CrtYd"))
    (pad "1" smd circle (at 0 0 270) (size 1 1) (layers "F.Cu" "F.Mask")
      (net 435 "Net-(U14-~{PWR_{EN}})") (pinfunction "1") (pintype "passive"))
  )
	(footprint "antmicro-footprints:TP_SMD_1mm" (layer "F.Cu")
    (at 124.95 66.8508)
    (property "Author" "Antmicro")
    (property "License" "Apache-2.0")
    (property "MPN" "")
    (property "Manufacturer" "")
    (property "Sheetfile" "interfaces.kicad_sch")
    (property "Sheetname" "Interfaces")
    (property "exclude_from_bom" "")
    (property "ki_description" "Test point 1mm SMD")
    (property "ki_keywords" "TESTPOINT")
    (attr exclude_from_pos_files exclude_from_bom)
    (fp_text reference "TP13" (at -3.34 0.4342) (layer "F.SilkS")
        (effects (font (size 0.7 0.7) (thickness 0.15)) (justify left bottom))
    )
    (fp_text value "TP_1mm_SMD" (at 0 1.4) (layer "F.Fab")
        (effects (font (size 0.7 0.7) (thickness 0.15)) (justify left bottom))
    )
    (fp_text user "${REFERENCE}" (at -0.5 2.8) (layer "F.Fab") hide
        (effects (font (size 0.7 0.7) (thickness 0.15)) (justify left bottom))
    )
    (fp_text user "License: Apache-2.0" (at -0.5 5.2) (layer "F.Fab") hide
        (effects (font (size 0.7 0.7) (thickness 0.15)) (justify left bottom))
    )
    (fp_text user "Author: Antmicro" (at -0.5 4) (layer "F.Fab") hide
        (effects (font (size 0.7 0.7) (thickness 0.15)) (justify left bottom))
    )
    (fp_circle (center 0 0) (end 0.6 0)
      (stroke (width 0.05) (type default)) (fill none) (layer "F.CrtYd"))
    (pad "1" smd circle (at 0 0) (size 1 1) (layers "F.Cu" "F.Mask")
      (net 388 "Net-(J6-ID)") (pinfunction "1") (pintype "passive"))
  )
)
